(kicad_pcb
	(version 20241229)
	(generator "pcbnew")
	(generator_version "9.0")
	(general
		(thickness 1.61)
		(legacy_teardrops no)
	)
	(paper "A3")
	(title_block
		(title "RDIMM DDR5 Tester")
		(date "2026-05-21")
		(rev "2.2.0")
		(company "Antmicro")
		(comment 9 "footprints 430-434 of 796")
	)
	(layers
		(0 "F.Cu" signal)
		(4 "In1.Cu" power)
		(6 "In2.Cu" mixed)
		(8 "In3.Cu" power)
		(10 "In4.Cu" mixed)
		(12 "In5.Cu" power)
		(14 "In6.Cu" mixed)
		(16 "In7.Cu" power)
		(18 "In8.Cu" power)
		(20 "In9.Cu" mixed)
		(22 "In10.Cu" power)
		(2 "B.Cu" signal)
		(9 "F.Adhes" user "F.Adhesive")
		(11 "B.Adhes" user "B.Adhesive")
		(13 "F.Paste" user)
		(15 "B.Paste" user)
		(5 "F.SilkS" user "F.Silkscreen")
		(7 "B.SilkS" user "B.Silkscreen")
		(1 "F.Mask" user)
		(3 "B.Mask" user)
		(17 "Dwgs.User" user "User.Drawings")
		(19 "Cmts.User" user "User.Comments")
		(21 "Eco1.User" user "User.Eco1")
		(23 "Eco2.User" user "User.Eco2")
		(25 "Edge.Cuts" user)
		(27 "Margin" user)
		(31 "F.CrtYd" user "F.Courtyard")
		(29 "B.CrtYd" user "B.Courtyard")
		(35 "F.Fab" user)
		(33 "B.Fab" user)
	)
	(footprint "antmicro-footprints:C_0402_1005Metric_EIA"
		(layer "B.Cu")
		(at 185 154.499999 -90)
		(descr "Capacitor SMD 0402 (1005 Metric), square (rectangular) end terminal, IPC_7351 nominal, (Body size source: IPC-SM-782 page 76, https://www.pcb-3d.com/wordpress/wp-content/uploads/ipc-sm-782a_amendment_1_and_2.pdf)")
		(tags "capacitor 0402")
		(property "Reference" "C41"
			(at -12.024999 30.625 90)
			(layer "B.SilkS")
			(effects
				(font
					(size 0.7 0.7)
					(thickness 0.15)
				)
				(justify left bottom mirror)
			)
		)
		(property "Value" "C_1u_25V_0402"
			(at 0 -1.169 90)
			(layer "B.Fab")
			(effects
				(font
					(size 0.7 0.7)
					(thickness 0.15)
				)
				(justify left bottom mirror)
			)
		)
		(property "Datasheet" "https://www.murata.com/products/productdetail?partno=GRM155R61E105KE11%23"
			(at 0 0 270)
			(layer "F.Fab")
			(hide yes)
			(effects
				(font
					(size 1.27 1.27)
					(thickness 0.15)
				)
			)
		)
		(property "MPN" "GRM155R61E105KE11J"
			(at 0 0 270)
			(unlocked yes)
			(layer "B.Fab")
			(hide yes)
			(effects
				(font
					(size 1 1)
					(thickness 0.15)
				)
				(justify mirror)
			)
		)
		(property "Manufacturer" "Murata"
			(at 0 0 270)
			(unlocked yes)
			(layer "B.Fab")
			(hide yes)
			(effects
				(font
					(size 1 1)
					(thickness 0.15)
				)
				(justify mirror)
			)
		)
		(property "License" "Apache-2.0"
			(at 0 0 270)
			(unlocked yes)
			(layer "B.Fab")
			(hide yes)
			(effects
				(font
					(size 1 1)
					(thickness 0.15)
				)
				(justify mirror)
			)
		)
		(property "Author" "Antmicro"
			(at 0 0 270)
			(unlocked yes)
			(layer "B.Fab")
			(hide yes)
			(effects
				(font
					(size 1 1)
					(thickness 0.15)
				)
				(justify mirror)
			)
		)
		(property "Val" "1u"
			(at 0 0 270)
			(unlocked yes)
			(layer "B.Fab")
			(hide yes)
			(effects
				(font
					(size 1 1)
					(thickness 0.15)
				)
				(justify mirror)
			)
		)
		(property "Voltage" "25V"
			(at 0 0 270)
			(unlocked yes)
			(layer "B.Fab")
			(hide yes)
			(effects
				(font
					(size 1 1)
					(thickness 0.15)
				)
				(justify mirror)
			)
		)
		(property "Dielectric" "X5R"
			(at 0 0 270)
			(unlocked yes)
			(layer "B.Fab")
			(hide yes)
			(effects
				(font
					(size 1 1)
					(thickness 0.15)
				)
				(justify mirror)
			)
		)
		(sheetname "/FPGA power/")
		(sheetfile "fpga-power.kicad_sch")
		(attr smd)
		(fp_rect
			(start -0.95 0.45)
			(end 0.95 -0.45)
			(stroke
				(width 0.05)
				(type default)
			)
			(fill no)
			(layer "B.CrtYd")
		)
		(fp_line
			(start -0.5 0.25)
			(end 0.498 0.25)
			(stroke
				(width 0.15)
				(type solid)
			)
			(layer "B.Fab")
		)
		(fp_line
			(start 0.498 0.25)
			(end 0.498 -0.248)
			(stroke
				(width 0.15)
				(type solid)
			)
			(layer "B.Fab")
		)
		(fp_line
			(start -0.5 -0.248)
			(end -0.5 0.25)
			(stroke
				(width 0.15)
				(type solid)
			)
			(layer "B.Fab")
		)
		(fp_line
			(start 0.498 -0.248)
			(end -0.5 -0.248)
			(stroke
				(width 0.15)
				(type solid)
			)
			(layer "B.Fab")
		)
		(fp_text user "${REFERENCE}"
			(at -0.9656 -3.169 90)
			(layer "B.Fab")
			(effects
				(font
					(size 0.7 0.7)
					(thickness 0.15)
				)
				(justify left bottom mirror)
			)
		)
		(fp_text user "License: Apache-2.0"
			(at -0.9656 -4.369 90)
			(layer "B.Fab")
			(effects
				(font
					(size 0.7 0.7)
					(thickness 0.15)
				)
				(justify left bottom mirror)
			)
		)
		(fp_text user "Author: Antmicro"
			(at -0.9656 -5.569 90)
			(layer "B.Fab")
			(effects
				(font
					(size 0.7 0.7)
					(thickness 0.15)
				)
				(justify left bottom mirror)
			)
		)
		(pad "1" smd roundrect
			(at -0.5 0 180)
			(size 0.6 0.6)
			(layers "B.Cu" "B.Mask" "B.Paste")
			(roundrect_rratio 0.25)
			(net 1 "GND")
			(pintype "passive")
		)
		(pad "2" smd roundrect
			(at 0.498 0 270)
			(size 0.6 0.6)
			(layers "B.Cu" "B.Mask" "B.Paste")
			(roundrect_rratio 0.25)
			(net 553 "+0V85")
			(pintype "passive")
		)
	)
	(footprint "antmicro-footprints:R_0402_1005Metric"
		(layer "B.Cu")
		(at 238.424499 185.849 180)
		(descr "Resistor SMD 0402")
		(tags "resistor SMD 0402")
		(property "Reference" "R150"
			(at -3.95 -0.5 0)
			(layer "B.SilkS")
			(effects
				(font
					(size 0.7 0.7)
					(thickness 0.15)
				)
				(justify left bottom mirror)
			)
		)
		(property "Value" "R_4k7_0402"
			(at -1.011843 -1.772047 0)
			(layer "B.Fab")
			(effects
				(font
					(size 0.7 0.7)
					(thickness 0.15)
				)
				(justify left bottom mirror)
			)
		)
		(property "Datasheet" "https://www.bourns.com/docs/product-datasheets/cr.pdf"
			(at 0 0 180)
			(layer "F.Fab")
			(hide yes)
			(effects
				(font
					(size 1.27 1.27)
					(thickness 0.15)
				)
			)
		)
		(property "Manufacturer" "Bourns"
			(at 0 0 180)
			(unlocked yes)
			(layer "B.Fab")
			(hide yes)
			(effects
				(font
					(size 1 1)
					(thickness 0.15)
				)
				(justify mirror)
			)
		)
		(property "MPN" "CR0402-FX-4701GLF"
			(at 0 0 180)
			(unlocked yes)
			(layer "B.Fab")
			(hide yes)
			(effects
				(font
					(size 1 1)
					(thickness 0.15)
				)
				(justify mirror)
			)
		)
		(property "Val" "4k7"
			(at 0 0 180)
			(unlocked yes)
			(layer "B.Fab")
			(hide yes)
			(effects
				(font
					(size 1 1)
					(thickness 0.15)
				)
				(justify mirror)
			)
		)
		(property "License" "Apache-2.0"
			(at 0 0 180)
			(unlocked yes)
			(layer "B.Fab")
			(hide yes)
			(effects
				(font
					(size 1 1)
					(thickness 0.15)
				)
				(justify mirror)
			)
		)
		(property "Author" "Antmicro"
			(at 0 0 180)
			(unlocked yes)
			(layer "B.Fab")
			(hide yes)
			(effects
				(font
					(size 1 1)
					(thickness 0.15)
				)
				(justify mirror)
			)
		)
		(property "Tolerance" "1%"
			(at 0 0 180)
			(unlocked yes)
			(layer "B.Fab")
			(hide yes)
			(effects
				(font
					(size 1 1)
					(thickness 0.15)
				)
				(justify mirror)
			)
		)
		(sheetname "/I^{2}C + I3C/")
		(sheetfile "i2c.kicad_sch")
		(attr smd)
		(fp_rect
			(start -0.925 0.47)
			(end 0.925 -0.47)
			(stroke
				(width 0.05)
				(type default)
			)
			(fill no)
			(layer "B.CrtYd")
		)
		(fp_rect
			(start -0.5 0.25)
			(end 0.5 -0.25)
			(stroke
				(width 0.15)
				(type solid)
			)
			(fill no)
			(layer "B.Fab")
		)
		(fp_text user "Author: Antmicro"
			(at -0.95 -4.169 0)
			(layer "B.Fab")
			(effects
				(font
					(size 0.7 0.7)
					(thickness 0.15)
				)
				(justify left bottom mirror)
			)
		)
		(fp_text user "License: Apache-2.0"
			(at -0.95 -5.169 0)
			(layer "B.Fab")
			(effects
				(font
					(size 0.7 0.7)
					(thickness 0.15)
				)
				(justify left bottom mirror)
			)
		)
		(fp_text user "${REFERENCE}"
			(at -0.95 -3.168 0)
			(layer "B.Fab")
			(effects
				(font
					(size 0.7 0.7)
					(thickness 0.15)
				)
				(justify left bottom mirror)
			)
		)
		(pad "1" smd roundrect
			(at -0.48 0 180)
			(size 0.59 0.64)
			(layers "B.Cu" "B.Mask" "B.Paste")
			(roundrect_rratio 0.25)
			(net 151 "+3V3")
			(pintype "passive")
		)
		(pad "2" smd roundrect
			(at 0.48 0 180)
			(size 0.59 0.64)
			(layers "B.Cu" "B.Mask" "B.Paste")
			(roundrect_rratio 0.25)
			(net 746 "/FPGA Config/FPGA_PWR.SDA")
			(pintype "passive")
		)
	)
	(footprint "antmicro-footprints:C_0402_1005Metric_EIA"
		(layer "B.Cu")
		(at 186 156.498 90)
		(descr "Capacitor SMD 0402 (1005 Metric), square (rectangular) end terminal, IPC_7351 nominal, (Body size source: IPC-SM-782 page 76, https://www.pcb-3d.com/wordpress/wp-content/uploads/ipc-sm-782a_amendment_1_and_2.pdf)")
		(tags "capacitor 0402")
		(property "Reference" "C47"
			(at 9.773 -30.65 90)
			(layer "B.SilkS")
			(effects
				(font
					(size 0.7 0.7)
					(thickness 0.15)
				)
				(justify right bottom mirror)
			)
		)
		(property "Value" "C_1u_25V_0402"
			(at 0 -1.169 90)
			(layer "B.Fab")
			(effects
				(font
					(size 0.7 0.7)
					(thickness 0.15)
				)
				(justify right bottom mirror)
			)
		)
		(property "Datasheet" "https://www.murata.com/products/productdetail?partno=GRM155R61E105KE11%23"
			(at 0 0 90)
			(layer "F.Fab")
			(hide yes)
			(effects
				(font
					(size 1.27 1.27)
					(thickness 0.15)
				)
			)
		)
		(property "MPN" "GRM155R61E105KE11J"
			(at 0 0 90)
			(unlocked yes)
			(layer "B.Fab")
			(hide yes)
			(effects
				(font
					(size 1 1)
					(thickness 0.15)
				)
				(justify mirror)
			)
		)
		(property "Manufacturer" "Murata"
			(at 0 0 90)
			(unlocked yes)
			(layer "B.Fab")
			(hide yes)
			(effects
				(font
					(size 1 1)
					(thickness 0.15)
				)
				(justify mirror)
			)
		)
		(property "License" "Apache-2.0"
			(at 0 0 90)
			(unlocked yes)
			(layer "B.Fab")
			(hide yes)
			(effects
				(font
					(size 1 1)
					(thickness 0.15)
				)
				(justify mirror)
			)
		)
		(property "Author" "Antmicro"
			(at 0 0 90)
			(unlocked yes)
			(layer "B.Fab")
			(hide yes)
			(effects
				(font
					(size 1 1)
					(thickness 0.15)
				)
				(justify mirror)
			)
		)
		(property "Val" "1u"
			(at 0 0 90)
			(unlocked yes)
			(layer "B.Fab")
			(hide yes)
			(effects
				(font
					(size 1 1)
					(thickness 0.15)
				)
				(justify mirror)
			)
		)
		(property "Voltage" "25V"
			(at 0 0 90)
			(unlocked yes)
			(layer "B.Fab")
			(hide yes)
			(effects
				(font
					(size 1 1)
					(thickness 0.15)
				)
				(justify mirror)
			)
		)
		(property "Dielectric" "X5R"
			(at 0 0 90)
			(unlocked yes)
			(layer "B.Fab")
			(hide yes)
			(effects
				(font
					(size 1 1)
					(thickness 0.15)
				)
				(justify mirror)
			)
		)
		(sheetname "/FPGA power/")
		(sheetfile "fpga-power.kicad_sch")
		(attr smd)
		(fp_rect
			(start -0.95 0.45)
			(end 0.95 -0.45)
			(stroke
				(width 0.05)
				(type default)
			)
			(fill no)
			(layer "B.CrtYd")
		)
		(fp_line
			(start 0.498 -0.248)
			(end -0.5 -0.248)
			(stroke
				(width 0.15)
				(type solid)
			)
			(layer "B.Fab")
		)
		(fp_line
			(start -0.5 -0.248)
			(end -0.5 0.25)
			(stroke
				(width 0.15)
				(type solid)
			)
			(layer "B.Fab")
		)
		(fp_line
			(start 0.498 0.25)
			(end 0.498 -0.248)
			(stroke
				(width 0.15)
				(type solid)
			)
			(layer "B.Fab")
		)
		(fp_line
			(start -0.5 0.25)
			(end 0.498 0.25)
			(stroke
				(width 0.15)
				(type solid)
			)
			(layer "B.Fab")
		)
		(fp_text user "License: Apache-2.0"
			(at -0.9656 -4.369 270)
			(layer "B.Fab")
			(effects
				(font
					(size 0.7 0.7)
					(thickness 0.15)
				)
				(justify left bottom mirror)
			)
		)
		(fp_text user "Author: Antmicro"
			(at -0.9656 -5.569 270)
			(layer "B.Fab")
			(effects
				(font
					(size 0.7 0.7)
					(thickness 0.15)
				)
				(justify left bottom mirror)
			)
		)
		(fp_text user "${REFERENCE}"
			(at -0.9656 -3.169 270)
			(layer "B.Fab")
			(effects
				(font
					(size 0.7 0.7)
					(thickness 0.15)
				)
				(justify left bottom mirror)
			)
		)
		(pad "1" smd roundrect
			(at -0.5 0)
			(size 0.6 0.6)
			(layers "B.Cu" "B.Mask" "B.Paste")
			(roundrect_rratio 0.25)
			(net 1 "GND")
			(pintype "passive")
		)
		(pad "2" smd roundrect
			(at 0.498 0 90)
			(size 0.6 0.6)
			(layers "B.Cu" "B.Mask" "B.Paste")
			(roundrect_rratio 0.25)
			(net 553 "+0V85")
			(pintype "passive")
		)
	)
	(footprint "antmicro-footprints:R_0402_1005Metric"
		(layer "B.Cu")
		(at 247.475 185.299)
		(descr "Resistor SMD 0402")
		(tags "resistor SMD 0402")
		(property "Reference" "R231"
			(at 0.825 0.5 0)
			(layer "B.SilkS")
			(effects
				(font
					(size 0.7 0.7)
					(thickness 0.15)
				)
				(justify right bottom mirror)
			)
		)
		(property "Value" "R_4k7_0402"
			(at -1.011843 -1.772047 0)
			(layer "B.Fab")
			(effects
				(font
					(size 0.7 0.7)
					(thickness 0.15)
				)
				(justify right bottom mirror)
			)
		)
		(property "Datasheet" "https://www.bourns.com/docs/product-datasheets/cr.pdf"
			(at 0 0 0)
			(layer "F.Fab")
			(hide yes)
			(effects
				(font
					(size 1.27 1.27)
					(thickness 0.15)
				)
			)
		)
		(property "MPN" "CR0402-FX-4701GLF"
			(at 0 0 0)
			(unlocked yes)
			(layer "B.Fab")
			(hide yes)
			(effects
				(font
					(size 1 1)
					(thickness 0.15)
				)
				(justify mirror)
			)
		)
		(property "Manufacturer" "Bourns"
			(at 0 0 0)
			(unlocked yes)
			(layer "B.Fab")
			(hide yes)
			(effects
				(font
					(size 1 1)
					(thickness 0.15)
				)
				(justify mirror)
			)
		)
		(property "License" "Apache-2.0"
			(at 0 0 0)
			(unlocked yes)
			(layer "B.Fab")
			(hide yes)
			(effects
				(font
					(size 1 1)
					(thickness 0.15)
				)
				(justify mirror)
			)
		)
		(property "Author" "Antmicro"
			(at 0 0 0)
			(unlocked yes)
			(layer "B.Fab")
			(hide yes)
			(effects
				(font
					(size 1 1)
					(thickness 0.15)
				)
				(justify mirror)
			)
		)
		(property "Val" "4k7"
			(at 0 0 0)
			(unlocked yes)
			(layer "B.Fab")
			(hide yes)
			(effects
				(font
					(size 1 1)
					(thickness 0.15)
				)
				(justify mirror)
			)
		)
		(property "Tolerance" "1%"
			(at 0 0 0)
			(unlocked yes)
			(layer "B.Fab")
			(hide yes)
			(effects
				(font
					(size 1 1)
					(thickness 0.15)
				)
				(justify mirror)
			)
		)
		(sheetname "/I^{2}C + I3C/")
		(sheetfile "i2c.kicad_sch")
		(attr smd)
		(fp_rect
			(start -0.925 0.47)
			(end 0.925 -0.47)
			(stroke
				(width 0.05)
				(type default)
			)
			(fill no)
			(layer "B.CrtYd")
		)
		(fp_rect
			(start -0.5 0.25)
			(end 0.5 -0.25)
			(stroke
				(width 0.15)
				(type solid)
			)
			(fill no)
			(layer "B.Fab")
		)
		(fp_text user "Author: Antmicro"
			(at -0.95 -4.169 180)
			(layer "B.Fab")
			(effects
				(font
					(size 0.7 0.7)
					(thickness 0.15)
				)
				(justify left bottom mirror)
			)
		)
		(fp_text user "License: Apache-2.0"
			(at -0.95 -5.169 180)
			(layer "B.Fab")
			(effects
				(font
					(size 0.7 0.7)
					(thickness 0.15)
				)
				(justify left bottom mirror)
			)
		)
		(fp_text user "${REFERENCE}"
			(at -0.95 -3.168 180)
			(layer "B.Fab")
			(effects
				(font
					(size 0.7 0.7)
					(thickness 0.15)
				)
				(justify left bottom mirror)
			)
		)
		(pad "1" smd roundrect
			(at -0.48 0)
			(size 0.59 0.64)
			(layers "B.Cu" "B.Mask" "B.Paste")
			(roundrect_rratio 0.25)
			(net 528 "/FPGA banks HD/FPGA_I3C.SDA")
			(pintype "passive")
		)
		(pad "2" smd roundrect
			(at 0.48 0)
			(size 0.59 0.64)
			(layers "B.Cu" "B.Mask" "B.Paste")
			(roundrect_rratio 0.25)
			(net 662 "Net-(Q22-D)")
			(pintype "passive")
		)
	)
	(footprint "antmicro-footprints:R_0402_1005Metric"
		(layer "B.Cu")
		(at 115.34 168.82)
		(descr "Resistor SMD 0402")
		(tags "resistor SMD 0402")
		(property "Reference" "R83"
			(at -1.09 1.53 0)
			(layer "B.SilkS")
			(effects
				(font
					(size 0.7 0.7)
					(thickness 0.15)
				)
				(justify right bottom mirror)
			)
		)
		(property "Value" "R_100k_0402"
			(at -1.011843 -1.772047 0)
			(layer "B.Fab")
			(effects
				(font
					(size 0.7 0.7)
					(thickness 0.15)
				)
				(justify right bottom mirror)
			)
		)
		(property "Datasheet" "https://www.bourns.com/docs/product-datasheets/cr.pdf"
			(at 0 0 0)
			(layer "F.Fab")
			(hide yes)
			(effects
				(font
					(size 1.27 1.27)
					(thickness 0.15)
				)
			)
		)
		(property "MPN" "CR0402-FX-1003GLF"
			(at 0 0 0)
			(unlocked yes)
			(layer "B.Fab")
			(hide yes)
			(effects
				(font
					(size 1 1)
					(thickness 0.15)
				)
				(justify mirror)
			)
		)
		(property "Manufacturer" "Bourns"
			(at 0 0 0)
			(unlocked yes)
			(layer "B.Fab")
			(hide yes)
			(effects
				(font
					(size 1 1)
					(thickness 0.15)
				)
				(justify mirror)
			)
		)
		(property "License" "Apache-2.0"
			(at 0 0 0)
			(unlocked yes)
			(layer "B.Fab")
			(hide yes)
			(effects
				(font
					(size 1 1)
					(thickness 0.15)
				)
				(justify mirror)
			)
		)
		(property "Author" "Antmicro"
			(at 0 0 0)
			(unlocked yes)
			(layer "B.Fab")
			(hide yes)
			(effects
				(font
					(size 1 1)
					(thickness 0.15)
				)
				(justify mirror)
			)
		)
		(property "Val" "100k"
			(at 0 0 0)
			(unlocked yes)
			(layer "B.Fab")
			(hide yes)
			(effects
				(font
					(size 1 1)
					(thickness 0.15)
				)
				(justify mirror)
			)
		)
		(property "Tolerance" "1%"
			(at 0 0 0)
			(unlocked yes)
			(layer "B.Fab")
			(hide yes)
			(effects
				(font
					(size 1 1)
					(thickness 0.15)
				)
				(justify mirror)
			)
		)
		(sheetname "/HDMI + SD Card/")
		(sheetfile "hdmi-sd-card.kicad_sch")
		(attr smd)
		(fp_rect
			(start -0.925 0.47)
			(end 0.925 -0.47)
			(stroke
				(width 0.05)
				(type default)
			)
			(fill no)
			(layer "B.CrtYd")
		)
		(fp_rect
			(start -0.5 0.25)
			(end 0.5 -0.25)
			(stroke
				(width 0.15)
				(type solid)
			)
			(fill no)
			(layer "B.Fab")
		)
		(fp_text user "${REFERENCE}"
			(at -0.95 -3.168 180)
			(layer "B.Fab")
			(effects
				(font
					(size 0.7 0.7)
					(thickness 0.15)
				)
				(justify left bottom mirror)
			)
		)
		(fp_text user "License: Apache-2.0"
			(at -0.95 -5.169 180)
			(layer "B.Fab")
			(effects
				(font
					(size 0.7 0.7)
					(thickness 0.15)
				)
				(justify left bottom mirror)
			)
		)
		(fp_text user "Author: Antmicro"
			(at -0.95 -4.169 180)
			(layer "B.Fab")
			(effects
				(font
					(size 0.7 0.7)
					(thickness 0.15)
				)
				(justify left bottom mirror)
			)
		)
		(pad "1" smd roundrect
			(at -0.48 0)
			(size 0.59 0.64)
			(layers "B.Cu" "B.Mask" "B.Paste")
			(roundrect_rratio 0.25)
			(net 1 "GND")
			(pintype "passive")
		)
		(pad "2" smd roundrect
			(at 0.48 0)
			(size 0.59 0.64)
			(layers "B.Cu" "B.Mask" "B.Paste")
			(roundrect_rratio 0.25)
			(net 500 "HDMI_IN_HPD")
			(pintype "passive")
		)
	)
)
